(kicad_pcb
	(version 20241229)
	(generator "pcbnew")
	(generator_version "9.0")
	(general
		(thickness 1.61)
		(legacy_teardrops no)
	)
	(paper "A3")
	(title_block
		(title "RDIMM DDR5 Tester")
		(date "2026-05-21")
		(rev "2.2.0")
		(company "Antmicro")
		(comment 9 "footprints 599-602 of 796")
	)
	(layers
		(0 "F.Cu" signal)
		(4 "In1.Cu" power)
		(6 "In2.Cu" mixed)
		(8 "In3.Cu" power)
		(10 "In4.Cu" mixed)
		(12 "In5.Cu" power)
		(14 "In6.Cu" mixed)
		(16 "In7.Cu" power)
		(18 "In8.Cu" power)
		(20 "In9.Cu" mixed)
		(22 "In10.Cu" power)
		(2 "B.Cu" signal)
		(9 "F.Adhes" user "F.Adhesive")
		(11 "B.Adhes" user "B.Adhesive")
		(13 "F.Paste" user)
		(15 "B.Paste" user)
		(5 "F.SilkS" user "F.Silkscreen")
		(7 "B.SilkS" user "B.Silkscreen")
		(1 "F.Mask" user)
		(3 "B.Mask" user)
		(17 "Dwgs.User" user "User.Drawings")
		(19 "Cmts.User" user "User.Comments")
		(21 "Eco1.User" user "User.Eco1")
		(23 "Eco2.User" user "User.Eco2")
		(25 "Edge.Cuts" user)
		(27 "Margin" user)
		(31 "F.CrtYd" user "F.Courtyard")
		(29 "B.CrtYd" user "B.Courtyard")
		(35 "F.Fab" user)
		(33 "B.Fab" user)
	)
	(footprint "antmicro-footprints:SC70-3"
		(layer "B.Cu")
		(at 254.05 120.275 90)
		(property "Reference" "Q26"
			(at -0.375 -1.4 270)
			(layer "B.SilkS")
			(effects
				(font
					(size 0.7 0.7)
					(thickness 0.15)
				)
				(justify right bottom mirror)
			)
		)
		(property "Value" "BSS138PW"
			(at 0 -2.3 90)
			(layer "B.Fab")
			(effects
				(font
					(size 0.7 0.7)
					(thickness 0.15)
				)
				(justify right bottom mirror)
			)
		)
		(property "Datasheet" "https://assets.nexperia.com/documents/data-sheet/BSS138PW.pdf"
			(at 0 0 90)
			(layer "F.Fab")
			(hide yes)
			(effects
				(font
					(size 1.27 1.27)
					(thickness 0.15)
				)
			)
		)
		(property "MPN" "BSS138PW"
			(at 0 0 90)
			(unlocked yes)
			(layer "B.Fab")
			(hide yes)
			(effects
				(font
					(size 1 1)
					(thickness 0.15)
				)
				(justify mirror)
			)
		)
		(property "Manufacturer" "Nexperia"
			(at 0 0 90)
			(unlocked yes)
			(layer "B.Fab")
			(hide yes)
			(effects
				(font
					(size 1 1)
					(thickness 0.15)
				)
				(justify mirror)
			)
		)
		(property "Author" "Antmicro"
			(at 0 0 90)
			(unlocked yes)
			(layer "B.Fab")
			(hide yes)
			(effects
				(font
					(size 1 1)
					(thickness 0.15)
				)
				(justify mirror)
			)
		)
		(property "License" "Apache-2.0"
			(at 0 0 90)
			(unlocked yes)
			(layer "B.Fab")
			(hide yes)
			(effects
				(font
					(size 1 1)
					(thickness 0.15)
				)
				(justify mirror)
			)
		)
		(sheetname "/DDR5 RDIMM/")
		(sheetfile "ddr5-rdimm.kicad_sch")
		(attr smd)
		(fp_line
			(start -0.3 -1)
			(end 0.627 -1.001)
			(stroke
				(width 0.15)
				(type solid)
			)
			(layer "B.SilkS")
		)
		(fp_line
			(start 0.627 -0.6)
			(end 0.627 -1.001)
			(stroke
				(width 0.15)
				(type solid)
			)
			(layer "B.SilkS")
		)
		(fp_line
			(start 0.627 0.6)
			(end 0.627 0.999)
			(stroke
				(width 0.15)
				(type solid)
			)
			(layer "B.SilkS")
		)
		(fp_line
			(start -0.3 1)
			(end 0.627 0.999)
			(stroke
				(width 0.15)
				(type solid)
			)
			(layer "B.SilkS")
		)
		(fp_line
			(start 0.9 -1.3)
			(end -0.9 -1.3)
			(stroke
				(width 0.05)
				(type solid)
			)
			(layer "B.CrtYd")
		)
		(fp_line
			(start -0.9 -1.3)
			(end -0.9 -1)
			(stroke
				(width 0.05)
				(type solid)
			)
			(layer "B.CrtYd")
		)
		(fp_line
			(start -0.9 -1)
			(end -1.4 -1)
			(stroke
				(width 0.05)
				(type solid)
			)
			(layer "B.CrtYd")
		)
		(fp_line
			(start -1.4 -1)
			(end -1.4 1)
			(stroke
				(width 0.05)
				(type solid)
			)
			(layer "B.CrtYd")
		)
		(fp_line
			(start 1.4 -0.4)
			(end 0.9 -0.4)
			(stroke
				(width 0.05)
				(type solid)
			)
			(layer "B.CrtYd")
		)
		(fp_line
			(start 0.9 -0.4)
			(end 0.9 -1.3)
			(stroke
				(width 0.05)
				(type solid)
			)
			(layer "B.CrtYd")
		)
		(fp_line
			(start 1.4 0.4)
			(end 1.4 -0.4)
			(stroke
				(width 0.05)
				(type solid)
			)
			(layer "B.CrtYd")
		)
		(fp_line
			(start 0.9 0.4)
			(end 1.4 0.4)
			(stroke
				(width 0.05)
				(type solid)
			)
			(layer "B.CrtYd")
		)
		(fp_line
			(start -0.9 1)
			(end -1.4 1)
			(stroke
				(width 0.05)
				(type solid)
			)
			(layer "B.CrtYd")
		)
		(fp_line
			(start 0.9 1.3)
			(end 0.9 0.4)
			(stroke
				(width 0.05)
				(type solid)
			)
			(layer "B.CrtYd")
		)
		(fp_line
			(start -0.9 1.3)
			(end -0.9 1)
			(stroke
				(width 0.05)
				(type solid)
			)
			(layer "B.CrtYd")
		)
		(fp_line
			(start -0.9 1.3)
			(end 0.9 1.3)
			(stroke
				(width 0.05)
				(type solid)
			)
			(layer "B.CrtYd")
		)
		(fp_rect
			(start -0.623 0.999)
			(end 0.627 -1.001)
			(stroke
				(width 0.15)
				(type solid)
			)
			(fill no)
			(layer "B.Fab")
		)
		(fp_text user "License: Apache-2.0"
			(at -1.45 -6.782 270)
			(layer "B.Fab")
			(effects
				(font
					(size 0.7 0.7)
					(thickness 0.15)
				)
				(justify left bottom mirror)
			)
		)
		(fp_text user "Author: Antmicro"
			(at -1.45 -5.782 270)
			(layer "B.Fab")
			(effects
				(font
					(size 0.7 0.7)
					(thickness 0.15)
				)
				(justify left bottom mirror)
			)
		)
		(fp_text user "${REFERENCE}"
			(at -1.45 -4.783 270)
			(layer "B.Fab")
			(effects
				(font
					(size 0.7 0.7)
					(thickness 0.15)
				)
				(justify left bottom mirror)
			)
		)
		(pad "1" smd rect
			(at -1.051 0.65)
			(size 0.6 0.6)
			(layers "B.Cu" "B.Mask" "B.Paste")
			(net 809 "VIN_MGMT_EN")
			(pinfunction "G")
			(pintype "passive")
		)
		(pad "2" smd rect
			(at -1.051 -0.65)
			(size 0.6 0.6)
			(layers "B.Cu" "B.Mask" "B.Paste")
			(net 1 "GND")
			(pinfunction "S")
			(pintype "passive")
		)
		(pad "3" smd rect
			(at 1.05 0)
			(size 0.6 0.6)
			(layers "B.Cu" "B.Mask" "B.Paste")
			(net 807 "Net-(Q26-D)")
			(pinfunction "D")
			(pintype "passive")
		)
	)
	(footprint "antmicro-footprints:C_0402_1005Metric"
		(layer "B.Cu")
		(at 120.411 166.36)
		(descr "Capacitor SMD 0402")
		(tags "capacitor SMD 0402")
		(property "Reference" "C93"
			(at 0.839 0.44 0)
			(layer "B.SilkS")
			(effects
				(font
					(size 0.7 0.7)
					(thickness 0.15)
				)
				(justify right bottom mirror)
			)
		)
		(property "Value" "C_100n_0402"
			(at -1.022927 -2.155213 0)
			(layer "B.Fab")
			(effects
				(font
					(size 0.7 0.7)
					(thickness 0.15)
				)
				(justify right bottom mirror)
			)
		)
		(property "Datasheet" "https://www.murata.com/products/productdetail?partno=GRM155R61H104KE14%23"
			(at 0 0 0)
			(layer "F.Fab")
			(hide yes)
			(effects
				(font
					(size 1.27 1.27)
					(thickness 0.15)
				)
			)
		)
		(property "MPN" "GRM155R61H104KE14D"
			(at 0 0 0)
			(unlocked yes)
			(layer "B.Fab")
			(hide yes)
			(effects
				(font
					(size 1 1)
					(thickness 0.15)
				)
				(justify mirror)
			)
		)
		(property "Manufacturer" "Murata"
			(at 0 0 0)
			(unlocked yes)
			(layer "B.Fab")
			(hide yes)
			(effects
				(font
					(size 1 1)
					(thickness 0.15)
				)
				(justify mirror)
			)
		)
		(property "License" "Apache-2.0"
			(at 0 0 0)
			(unlocked yes)
			(layer "B.Fab")
			(hide yes)
			(effects
				(font
					(size 1 1)
					(thickness 0.15)
				)
				(justify mirror)
			)
		)
		(property "Author" "Antmicro"
			(at 0 0 0)
			(unlocked yes)
			(layer "B.Fab")
			(hide yes)
			(effects
				(font
					(size 1 1)
					(thickness 0.15)
				)
				(justify mirror)
			)
		)
		(property "Val" "100n"
			(at 0 0 0)
			(unlocked yes)
			(layer "B.Fab")
			(hide yes)
			(effects
				(font
					(size 1 1)
					(thickness 0.15)
				)
				(justify mirror)
			)
		)
		(property "Voltage" "50V"
			(at 0 0 0)
			(unlocked yes)
			(layer "B.Fab")
			(hide yes)
			(effects
				(font
					(size 1 1)
					(thickness 0.15)
				)
				(justify mirror)
			)
		)
		(property "Dielectric" "X5R"
			(at 0 0 0)
			(unlocked yes)
			(layer "B.Fab")
			(hide yes)
			(effects
				(font
					(size 1 1)
					(thickness 0.15)
				)
				(justify mirror)
			)
		)
		(property "Public" ""
			(at 0 0 0)
			(unlocked yes)
			(layer "B.Fab")
			(hide yes)
			(effects
				(font
					(size 1 1)
					(thickness 0.15)
				)
				(justify mirror)
			)
		)
		(sheetname "/HDMI + SD Card/")
		(sheetfile "hdmi-sd-card.kicad_sch")
		(attr smd)
		(fp_rect
			(start -0.925 0.47)
			(end 0.925 -0.47)
			(stroke
				(width 0.05)
				(type default)
			)
			(fill no)
			(layer "B.CrtYd")
		)
		(fp_line
			(start -0.494 -0.248)
			(end -0.494 0.25)
			(stroke
				(width 0.15)
				(type solid)
			)
			(layer "B.Fab")
		)
		(fp_line
			(start -0.494 0.25)
			(end 0.504 0.25)
			(stroke
				(width 0.15)
				(type solid)
			)
			(layer "B.Fab")
		)
		(fp_line
			(start 0.504 -0.248)
			(end -0.494 -0.248)
			(stroke
				(width 0.15)
				(type solid)
			)
			(layer "B.Fab")
		)
		(fp_line
			(start 0.504 0.25)
			(end 0.504 -0.248)
			(stroke
				(width 0.15)
				(type solid)
			)
			(layer "B.Fab")
		)
		(fp_text user "${REFERENCE}"
			(at -0.939 -4.599 180)
			(layer "B.Fab")
			(effects
				(font
					(size 0.7 0.7)
					(thickness 0.15)
				)
				(justify left bottom mirror)
			)
		)
		(fp_text user "Author: Antmicro"
			(at -0.939 -3.399 180)
			(layer "B.Fab")
			(effects
				(font
					(size 0.7 0.7)
					(thickness 0.15)
				)
				(justify left bottom mirror)
			)
		)
		(fp_text user "License: Apache-2.0"
			(at -0.939 -5.799 180)
			(layer "B.Fab")
			(effects
				(font
					(size 0.7 0.7)
					(thickness 0.15)
				)
				(justify left bottom mirror)
			)
		)
		(pad "1" smd roundrect
			(at -0.48 0)
			(size 0.59 0.64)
			(layers "B.Cu" "B.Mask" "B.Paste")
			(roundrect_rratio 0.25)
			(net 297 "/HDMI + SD Card/HDMI_IN_5V")
			(pintype "passive")
		)
		(pad "2" smd roundrect
			(at 0.48 0)
			(size 0.59 0.64)
			(layers "B.Cu" "B.Mask" "B.Paste")
			(roundrect_rratio 0.25)
			(net 1 "GND")
			(pintype "passive")
		)
	)
	(footprint "antmicro-footprints:C_0805_2012Metric"
		(layer "B.Cu")
		(at 203.5 162.4 90)
		(descr "Capacitor SMD 0805")
		(tags "capacitor SMD 0805")
		(property "Reference" "C240"
			(at -1.49 2.09 90)
			(layer "B.SilkS")
			(effects
				(font
					(size 0.7 0.7)
					(thickness 0.15)
				)
				(justify right bottom mirror)
			)
		)
		(property "Value" "C_100u_0805"
			(at -2.055717 -1.963152 90)
			(layer "B.Fab")
			(effects
				(font
					(size 0.7 0.7)
					(thickness 0.15)
				)
				(justify right bottom mirror)
			)
		)
		(property "Datasheet" "https://www.murata.com/products/productdetail?partno=GRM21BR60J107ME15%23"
			(at 0 0 90)
			(layer "F.Fab")
			(hide yes)
			(effects
				(font
					(size 1.27 1.27)
					(thickness 0.15)
				)
			)
		)
		(property "MPN" "GRM21BR60J107ME15L"
			(at 0 0 90)
			(unlocked yes)
			(layer "B.Fab")
			(hide yes)
			(effects
				(font
					(size 1 1)
					(thickness 0.15)
				)
				(justify mirror)
			)
		)
		(property "Manufacturer" "Murata"
			(at 0 0 90)
			(unlocked yes)
			(layer "B.Fab")
			(hide yes)
			(effects
				(font
					(size 1 1)
					(thickness 0.15)
				)
				(justify mirror)
			)
		)
		(property "License" "Apache-2.0"
			(at 0 0 90)
			(unlocked yes)
			(layer "B.Fab")
			(hide yes)
			(effects
				(font
					(size 1 1)
					(thickness 0.15)
				)
				(justify mirror)
			)
		)
		(property "Author" "Antmicro"
			(at 0 0 90)
			(unlocked yes)
			(layer "B.Fab")
			(hide yes)
			(effects
				(font
					(size 1 1)
					(thickness 0.15)
				)
				(justify mirror)
			)
		)
		(property "Val" "100u"
			(at 0 0 90)
			(unlocked yes)
			(layer "B.Fab")
			(hide yes)
			(effects
				(font
					(size 1 1)
					(thickness 0.15)
				)
				(justify mirror)
			)
		)
		(property "Voltage" ""
			(at 0 0 90)
			(unlocked yes)
			(layer "B.Fab")
			(hide yes)
			(effects
				(font
					(size 1 1)
					(thickness 0.15)
				)
				(justify mirror)
			)
		)
		(property "Dielectric" ""
			(at 0 0 90)
			(unlocked yes)
			(layer "B.Fab")
			(hide yes)
			(effects
				(font
					(size 1 1)
					(thickness 0.15)
				)
				(justify mirror)
			)
		)
		(property "Public" "False"
			(at 0 0 90)
			(unlocked yes)
			(layer "B.Fab")
			(hide yes)
			(effects
				(font
					(size 1 1)
					(thickness 0.15)
				)
				(justify mirror)
			)
		)
		(sheetname "/FPGA power/")
		(sheetfile "fpga-power.kicad_sch")
		(attr smd)
		(fp_line
			(start -0.3 -0.7)
			(end 0.3 -0.7)
			(stroke
				(width 0.15)
				(type solid)
			)
			(layer "B.SilkS")
		)
		(fp_line
			(start -0.3 0.7)
			(end 0.3 0.7)
			(stroke
				(width 0.15)
				(type solid)
			)
			(layer "B.SilkS")
		)
		(fp_rect
			(start 1.95 0.9)
			(end -1.95 -0.9)
			(stroke
				(width 0.05)
				(type default)
			)
			(fill no)
			(layer "B.CrtYd")
		)
		(fp_rect
			(start -0.95 0.675)
			(end 0.95 -0.675)
			(stroke
				(width 0.15)
				(type solid)
			)
			(fill no)
			(layer "B.Fab")
		)
		(fp_text user "License: Apache-2.0"
			(at -1.9 -4.947 270)
			(layer "B.Fab")
			(effects
				(font
					(size 0.7 0.7)
					(thickness 0.15)
				)
				(justify left bottom mirror)
			)
		)
		(fp_text user "${REFERENCE}"
			(at -1.9 -3.947 270)
			(layer "B.Fab")
			(effects
				(font
					(size 0.7 0.7)
					(thickness 0.15)
				)
				(justify left bottom mirror)
			)
		)
		(fp_text user "Author: Antmicro"
			(at -1.9 -5.947 270)
			(layer "B.Fab")
			(effects
				(font
					(size 0.7 0.7)
					(thickness 0.15)
				)
				(justify left bottom mirror)
			)
		)
		(pad "1" smd roundrect
			(at -1.1 0 90)
			(size 1.2 1.3)
			(layers "B.Cu" "B.Mask" "B.Paste")
			(roundrect_rratio 0.25)
			(net 1 "GND")
			(pintype "passive")
		)
		(pad "2" smd roundrect
			(at 1.1 0 90)
			(size 1.2 1.3)
			(layers "B.Cu" "B.Mask" "B.Paste")
			(roundrect_rratio 0.25)
			(net 553 "+0V85")
			(pintype "passive")
		)
	)
	(footprint "antmicro-footprints:C_0402_1005Metric"
		(layer "B.Cu")
		(at 122.95 150.61)
		(descr "Capacitor SMD 0402")
		(tags "capacitor SMD 0402")
		(property "Reference" "C304"
			(at 2.3 1.242 0)
			(layer "B.SilkS")
			(effects
				(font
					(size 0.7 0.7)
					(thickness 0.15)
				)
				(justify right bottom mirror)
			)
		)
		(property "Value" "C_100n_0402"
			(at -1.022927 -2.155213 0)
			(layer "B.Fab")
			(effects
				(font
					(size 0.7 0.7)
					(thickness 0.15)
				)
				(justify right bottom mirror)
			)
		)
		(property "Datasheet" "https://www.murata.com/products/productdetail?partno=GRM155R61H104KE14%23"
			(at 0 0 0)
			(layer "F.Fab")
			(hide yes)
			(effects
				(font
					(size 1.27 1.27)
					(thickness 0.15)
				)
			)
		)
		(property "Manufacturer" "Murata"
			(at 0 0 0)
			(unlocked yes)
			(layer "B.Fab")
			(hide yes)
			(effects
				(font
					(size 1 1)
					(thickness 0.15)
				)
				(justify mirror)
			)
		)
		(property "MPN" "GRM155R61H104KE14D"
			(at 0 0 0)
			(unlocked yes)
			(layer "B.Fab")
			(hide yes)
			(effects
				(font
					(size 1 1)
					(thickness 0.15)
				)
				(justify mirror)
			)
		)
		(property "Val" "100n"
			(at 0 0 0)
			(unlocked yes)
			(layer "B.Fab")
			(hide yes)
			(effects
				(font
					(size 1 1)
					(thickness 0.15)
				)
				(justify mirror)
			)
		)
		(property "License" "Apache-2.0"
			(at 0 0 0)
			(unlocked yes)
			(layer "B.Fab")
			(hide yes)
			(effects
				(font
					(size 1 1)
					(thickness 0.15)
				)
				(justify mirror)
			)
		)
		(property "Author" "Antmicro"
			(at 0 0 0)
			(unlocked yes)
			(layer "B.Fab")
			(hide yes)
			(effects
				(font
					(size 1 1)
					(thickness 0.15)
				)
				(justify mirror)
			)
		)
		(property "Voltage" "50V"
			(at 0 0 0)
			(unlocked yes)
			(layer "B.Fab")
			(hide yes)
			(effects
				(font
					(size 1 1)
					(thickness 0.15)
				)
				(justify mirror)
			)
		)
		(property "Dielectric" "X5R"
			(at 0 0 0)
			(unlocked yes)
			(layer "B.Fab")
			(hide yes)
			(effects
				(font
					(size 1 1)
					(thickness 0.15)
				)
				(justify mirror)
			)
		)
		(sheetname "/FPGA MGT Interface/")
		(sheetfile "fpga-mgt.kicad_sch")
		(attr smd)
		(fp_rect
			(start -0.925 0.47)
			(end 0.925 -0.47)
			(stroke
				(width 0.05)
				(type default)
			)
			(fill no)
			(layer "B.CrtYd")
		)
		(fp_line
			(start -0.494 -0.248)
			(end -0.494 0.25)
			(stroke
				(width 0.15)
				(type solid)
			)
			(layer "B.Fab")
		)
		(fp_line
			(start -0.494 0.25)
			(end 0.504 0.25)
			(stroke
				(width 0.15)
				(type solid)
			)
			(layer "B.Fab")
		)
		(fp_line
			(start 0.504 -0.248)
			(end -0.494 -0.248)
			(stroke
				(width 0.15)
				(type solid)
			)
			(layer "B.Fab")
		)
		(fp_line
			(start 0.504 0.25)
			(end 0.504 -0.248)
			(stroke
				(width 0.15)
				(type solid)
			)
			(layer "B.Fab")
		)
		(fp_text user "License: Apache-2.0"
			(at -0.939 -5.799 180)
			(layer "B.Fab")
			(effects
				(font
					(size 0.7 0.7)
					(thickness 0.15)
				)
				(justify left bottom mirror)
			)
		)
		(fp_text user "Author: Antmicro"
			(at -0.939 -3.399 180)
			(layer "B.Fab")
			(effects
				(font
					(size 0.7 0.7)
					(thickness 0.15)
				)
				(justify left bottom mirror)
			)
		)
		(fp_text user "${REFERENCE}"
			(at -0.939 -4.599 180)
			(layer "B.Fab")
			(effects
				(font
					(size 0.7 0.7)
					(thickness 0.15)
				)
				(justify left bottom mirror)
			)
		)
		(pad "1" smd roundrect
			(at -0.48 0)
			(size 0.59 0.64)
			(layers "B.Cu" "B.Mask" "B.Paste")
			(roundrect_rratio 0.25)
			(net 346 "/FPGA MGT Interface/HDMI_IN.D1_N")
			(pintype "passive")
		)
		(pad "2" smd roundrect
			(at 0.48 0)
			(size 0.59 0.64)
			(layers "B.Cu" "B.Mask" "B.Paste")
			(roundrect_rratio 0.25)
			(net 650 "/FPGA MGT Interface/HDMI_FPGA.RX1_N")
			(pintype "passive")
		)
	)
)
